# BASEBOARD_FAB2 (Tioga Pass) — schematic parts with pin connectivity, parts 2348–2348 of 4751; source: Cadence DE-HDL packaged netlist (pstxprt.dat, pstxnet.dat, pstchip.dat)

J1A2  SCONN288_H44441004  SCONN  pkg PIP  page 85
  1  \12v\(1)  = P12V_NVDIMM_KLM
  2  VSS(93)  GROUND  = GND
  3  DQ(4)  BI  = M_L_DQ<5>
  4  VSS(92)  GROUND  = GND
  5  DQ(0)  BI  = M_L_DQ<1>
  6  VSS(91)  GROUND  = GND
  7  DQS9P  BI  = M_L_DQS_DP<9>
  8  DQS9N  BI  = M_L_DQS_DN<9>
  9  VSS(90)  GROUND  = GND
  10  DQ(6)  BI  = M_L_DQ<7>
  11  VSS(89)  GROUND  = GND
  12  DQ(2)  BI  = M_L_DQ<3>
  13  VSS(88)  GROUND  = GND
  14  DQ(12)  BI  = M_L_DQ<13>
  15  VSS(87)  GROUND  = GND
  16  DQ(8)  BI  = M_L_DQ<9>
  17  VSS(86)  GROUND  = GND
  18  DQS10P  BI  = M_L_DQS_DP<10>
  19  DQS10N  BI  = M_L_DQS_DN<10>
  20  VSS(85)  GROUND  = GND
  21  DQ(14)  BI  = M_L_DQ<15>
  22  VSS(84)  GROUND  = GND
  23  DQ(10)  BI  = M_L_DQ<11>
  24  VSS(83)  GROUND  = GND
  25  DQ(20)  BI  = M_L_DQ<21>
  26  VSS(82)  GROUND  = GND
  27  DQ(16)  BI  = M_L_DQ<17>
  28  VSS(81)  GROUND  = GND
  29  DQS11P  BI  = M_L_DQS_DP<11>
  30  DQS11N  BI  = M_L_DQS_DN<11>
  31  VSS(80)  GROUND  = GND
  32  DQ(22)  BI  = M_L_DQ<23>
  33  VSS(79)  GROUND  = GND
  34  DQ(18)  BI  = M_L_DQ<19>
  35  VSS(78)  GROUND  = GND
  36  DQ(28)  BI  = M_L_DQ<29>
  37  VSS(77)  GROUND  = GND
  38  DQ(24)  BI  = M_L_DQ<25>
  39  VSS(76)  GROUND  = GND
  40  DQS12P  BI  = M_L_DQS_DP<12>
  41  DQS12N  BI  = M_L_DQS_DN<12>
  42  VSS(75)  GROUND  = GND
  43  DQ(30)  BI  = M_L_DQ<31>
  44  VSS(74)  GROUND  = GND
  45  DQ(26)  BI  = M_L_DQ<27>
  46  VSS(73)  GROUND  = GND
  47  CB(4)  BI  = M_L_ECC<5>
  48  VSS(72)  GROUND  = GND
  49  CB(0)  BI  = M_L_ECC<1>
  50  VSS(71)  GROUND  = GND
  51  DQS17P  BI  = M_L_DQS_DP<17>
  52  DQS17N  BI  = M_L_DQS_DN<17>
  53  VSS(70)  GROUND  = GND
  54  CB(6)  BI  = M_L_ECC<7>
  55  VSS(69)  GROUND  = GND
  56  CB(2)  BI  = M_L_ECC<3>
  57  VSS(68)  GROUND  = GND
  58  RESET_N  BI  = M_KLM_RST_N
  59  VDD(25)  POWER  = PVDDQ_KLM
  60  CKE(0)  BI  = M_L_CKE<0>
  61  VDD(24)  POWER  = PVDDQ_KLM
  62  ACT_N  BI  = M_L_ACT_N
  63  BG(0)  BI  = M_L_BG<0>
  64  VDD(23)  POWER  = PVDDQ_KLM
  65  A12  BI  = M_L_MA<12>
  66  A9  BI  = M_L_MA<9>
  67  VDD(22)  POWER  = PVDDQ_KLM
  68  A8  BI  = M_L_MA<8>
  69  A6  BI  = M_L_MA<6>
  70  VDD(21)  POWER  = PVDDQ_KLM
  71  A3  BI  = M_L_MA<3>
  72  A1  BI  = M_L_MA<1>
  73  VDD(20)  POWER  = PVDDQ_KLM
  74  CK0P  BI  = M_L_CLK_DP<0>
  75  CK0N  BI  = M_L_CLK_DN<0>
  76  VDD(19)  POWER  = PVDDQ_KLM
  77  VTT(1)  POWER  = PVTT_KLM
  78  EVENT_N  BI  = FM_DIMM_EVENT_COD_N
  79  A0  BI  = M_L_MA<0>
  80  VDD(18)  POWER  = PVDDQ_KLM
  81  BA(0)  BI  = M_L_BA<0>
  82  A16_RAS_N  BI  = M_L_MA<16>
  83  VDD(17)  POWER  = PVDDQ_KLM
  84  S0_N  BI  = M_L_CS_N<0>
  85  VDD(16)  POWER  = PVDDQ_KLM
  86  A15_CAS_N  BI  = M_L_MA<15>
  87  ODT(0)  BI  = M_L_ODT<0>
  88  VDD(15)  POWER  = PVDDQ_KLM
  89  S1_N  BI  = M_L_CS_N<1>
  90  VDD(14)  POWER  = PVDDQ_KLM
  91  ODT(1)  BI  = M_L_ODT<1>
  92  VDD(13)  POWER  = PVDDQ_KLM
  93  S2_N_C(0)  BI  = M_L_CS_N<2>
  94  VSS(67)  GROUND  = GND
  95  DQ(36)  BI  = M_L_DQ<37>
  96  VSS(66)  GROUND  = GND
  97  DQ(32)  BI  = M_L_DQ<33>
  98  VSS(65)  GROUND  = GND
  99  DQS13P  BI  = M_L_DQS_DP<13>
  100  DQS13N  BI  = M_L_DQS_DN<13>
  101  VSS(64)  GROUND  = GND
  102  DQ(38)  BI  = M_L_DQ<39>
  103  VSS(63)  GROUND  = GND
  104  DQ(34)  BI  = M_L_DQ<35>
  105  VSS(62)  GROUND  = GND
  106  DQ(44)  BI  = M_L_DQ<45>
  107  VSS(61)  GROUND  = GND
  108  DQ(40)  BI  = M_L_DQ<41>
  109  VSS(60)  GROUND  = GND
  110  DQS14P  BI  = M_L_DQS_DP<14>
  111  DQS14N  BI  = M_L_DQS_DN<14>
  112  VSS(59)  GROUND  = GND
  113  DQ(46)  BI  = M_L_DQ<47>
  114  VSS(58)  GROUND  = GND
  115  DQ(42)  BI  = M_L_DQ<43>
  116  VSS(57)  GROUND  = GND
  117  DQ(52)  BI  = M_L_DQ<53>
  118  VSS(56)  GROUND  = GND
  119  DQ(48)  BI  = M_L_DQ<49>
  120  VSS(55)  GROUND  = GND
  121  DQS15P  BI  = M_L_DQS_DP<15>
  122  DQS15N  BI  = M_L_DQS_DN<15>
  123  VSS(54)  GROUND  = GND
  124  DQ(54)  BI  = M_L_DQ<55>
  125  VSS(53)  GROUND  = GND
  126  DQ(50)  BI  = M_L_DQ<51>
  127  VSS(52)  GROUND  = GND
  128  DQ(60)  BI  = M_L_DQ<61>
  129  VSS(51)  GROUND  = GND
  130  DQ(56)  BI  = M_L_DQ<57>
  131  VSS(50)  GROUND  = GND
  132  DQS16P  BI  = M_L_DQS_DP<16>
  133  DQS16N  BI  = M_L_DQS_DN<16>
  134  VSS(49)  GROUND  = GND
  135  DQ(62)  BI  = M_L_DQ<63>
  136  VSS(48)  GROUND  = GND
  137  DQ(58)  BI  = M_L_DQ<59>
  138  VSS(47)  GROUND  = GND
  139  SA(0)  BI  = GND
  140  SA(1)  BI  = PVPP_KLM
  141  SCL  BI  = SMB_DDR_KLM_VPP_SCL
  142  VPP(4)  POWER  = PVPP_KLM
  143  VPP(3)  POWER  = PVPP_KLM
  144  RFU(2)  BI  = TP_CH_L_DIMM_L0_RFU_2
  145  \12v\(0)  = P12V_NVDIMM_KLM
  146  VREFCA  BI  = M_L_VREF
  147  VSS(46)  GROUND  = GND
  148  DQ(5)  BI  = M_L_DQ<4>
  149  VSS(45)  GROUND  = GND
  150  DQ(1)  BI  = M_L_DQ<0>
  151  VSS(44)  GROUND  = GND
  152  DQS0N  BI  = M_L_DQS_DN<0>
  153  DQS0P  BI  = M_L_DQS_DP<0>
  154  VSS(43)  GROUND  = GND
  155  DQ(7)  BI  = M_L_DQ<6>
  156  VSS(42)  GROUND  = GND
  157  DQ(3)  BI  = M_L_DQ<2>
  158  VSS(41)  GROUND  = GND
  159  DQ(13)  BI  = M_L_DQ<12>
  160  VSS(40)  GROUND  = GND
  161  DQ(9)  BI  = M_L_DQ<8>
  162  VSS(39)  GROUND  = GND
  163  DQS1N  BI  = M_L_DQS_DN<1>
  164  DQS1P  BI  = M_L_DQS_DP<1>
  165  VSS(38)  GROUND  = GND
  166  DQ(15)  BI  = M_L_DQ<14>
  167  VSS(37)  GROUND  = GND
  168  DQ(11)  BI  = M_L_DQ<10>
  169  VSS(36)  GROUND  = GND
  170  DQ(21)  BI  = M_L_DQ<20>
  171  VSS(35)  GROUND  = GND
  172  DQ(17)  BI  = M_L_DQ<16>
  173  VSS(34)  GROUND  = GND
  174  DQS2N  BI  = M_L_DQS_DN<2>
  175  DQS2P  BI  = M_L_DQS_DP<2>
  176  VSS(33)  GROUND  = GND
  177  DQ(23)  BI  = M_L_DQ<22>
  178  VSS(32)  GROUND  = GND
  179  DQ(19)  BI  = M_L_DQ<18>
  180  VSS(31)  GROUND  = GND
  181  DQ(29)  BI  = M_L_DQ<28>
  182  VSS(30)  GROUND  = GND
  183  DQ(25)  BI  = M_L_DQ<24>
  184  VSS(29)  GROUND  = GND
  185  DQS3N  BI  = M_L_DQS_DN<3>
  186  DQS3P  BI  = M_L_DQS_DP<3>
  187  VSS(28)  GROUND  = GND
  188  DQ(31)  BI  = M_L_DQ<30>
  189  VSS(27)  GROUND  = GND
  190  DQ(27)  BI  = M_L_DQ<26>
  191  VSS(26)  GROUND  = GND
  192  CB(5)  BI  = M_L_ECC<4>
  193  VSS(25)  GROUND  = GND
  194  CB(1)  BI  = M_L_ECC<0>
  195  VSS(24)  GROUND  = GND
  196  DQS8N  BI  = M_L_DQS_DN<8>
  197  DQS8P  BI  = M_L_DQS_DP<8>
  198  VSS(23)  GROUND  = GND
  199  CB(7)  BI  = M_L_ECC<6>
  200  VSS(22)  GROUND  = GND
  201  CB(3)  BI  = M_L_ECC<2>
  202  VSS(21)  GROUND  = GND
  203  CKE(1)  BI  = M_L_CKE<1>
  204  VDD(12)  POWER  = PVDDQ_KLM
  205  RFU(0)  BI  = TP_CH_L_DIMM_L0_RFU_0
  206  VDD(11)  POWER  = PVDDQ_KLM
  207  BG(1)  BI  = M_L_BG<1>
  208  ALERT_N  BI  = M_L_ALERT_N
  209  VDD(10)  POWER  = PVDDQ_KLM
  210  A11  BI  = M_L_MA<11>
  211  A7  BI  = M_L_MA<7>
  212  VDD(9)  POWER  = PVDDQ_KLM
  213  A5  BI  = M_L_MA<5>
  214  A4  BI  = M_L_MA<4>
  215  VDD(8)  POWER  = PVDDQ_KLM
  216  A2  BI  = M_L_MA<2>
  217  VDD(7)  POWER  = PVDDQ_KLM
  218  CK1P  BI  = M_L_CLK_DP<1>
  219  CK1N  BI  = M_L_CLK_DN<1>
  220  VDD(6)  POWER  = PVDDQ_KLM
  221  VTT(0)  POWER  = PVTT_KLM
  222  PAR  BI  = M_L_PAR
  223  VDD(5)  POWER  = PVDDQ_KLM
  224  BA(1)  BI  = M_L_BA<1>
  225  A10  BI  = M_L_MA<10>
  226  VDD(4)  POWER  = PVDDQ_KLM
  227  RFU(1)  BI  = TP_CH_L_DIMM_L0_RFU_1
  228  A14_WE_N  BI  = M_L_MA<14>
  229  VDD(3)  POWER  = PVDDQ_KLM
  230  SAVE_N_NC  BI  = FM_ADR_COMPLETE_KLM_N
  231  VDD(2)  POWER  = PVDDQ_KLM
  232  A13  BI  = M_L_MA<13>
  233  VDD(1)  POWER  = PVDDQ_KLM
  234  A17  BI  = M_L_MA<17>
  235  C(2)  BI  = M_L_C<2>
  236  VDD(0)  POWER  = PVDDQ_KLM
  237  S3_N_C(1)  BI  = M_L_CS_N<3>
  238  SA(2)  BI  = GND
  239  VSS(20)  GROUND  = GND
  240  DQ(37)  BI  = M_L_DQ<36>
  241  VSS(19)  GROUND  = GND
  242  DQ(33)  BI  = M_L_DQ<32>
  243  VSS(18)  GROUND  = GND
  244  DQS4N  BI  = M_L_DQS_DN<4>
  245  DQS4P  BI  = M_L_DQS_DP<4>
  246  VSS(17)  GROUND  = GND
  247  DQ(39)  BI  = M_L_DQ<38>
  248  VSS(16)  GROUND  = GND
  249  DQ(35)  BI  = M_L_DQ<34>
  250  VSS(15)  GROUND  = GND
  251  DQ(45)  BI  = M_L_DQ<44>
  252  VSS(14)  GROUND  = GND
  253  DQ(41)  BI  = M_L_DQ<40>
  254  VSS(13)  GROUND  = GND
  255  DQS5N  BI  = M_L_DQS_DN<5>
  256  DQS5P  BI  = M_L_DQS_DP<5>
  257  VSS(12)  GROUND  = GND
  258  DQ(47)  BI  = M_L_DQ<46>
  259  VSS(11)  GROUND  = GND
  260  DQ(43)  BI  = M_L_DQ<42>
  261  VSS(10)  GROUND  = GND
  262  DQ(53)  BI  = M_L_DQ<52>
  263  VSS(9)  GROUND  = GND
  264  DQ(49)  BI  = M_L_DQ<48>
  265  VSS(8)  GROUND  = GND
  266  DQS6N  BI  = M_L_DQS_DN<6>
  267  DQS6P  BI  = M_L_DQS_DP<6>
  268  VSS(7)  GROUND  = GND
  269  DQ(55)  BI  = M_L_DQ<54>
  270  VSS(6)  GROUND  = GND
  271  DQ(51)  BI  = M_L_DQ<50>
  272  VSS(5)  GROUND  = GND
  273  DQ(61)  BI  = M_L_DQ<60>
  274  VSS(4)  GROUND  = GND
  275  DQ(57)  BI  = M_L_DQ<56>
  276  VSS(3)  GROUND  = GND
  277  DQS7N  BI  = M_L_DQS_DN<7>
  278  DQS7P  BI  = M_L_DQS_DP<7>
  279  VSS(2)  GROUND  = GND
  280  DQ(63)  BI  = M_L_DQ<62>
  281  VSS(1)  GROUND  = GND
  282  DQ(59)  BI  = M_L_DQ<58>
  283  VSS(0)  GROUND  = GND
  284  VDDSPD  BI  = PVPP_KLM
  285  SDA  BI  = SMB_DDR_KLM_VPP_SDA
  286  VPP(1)  POWER  = PVPP_KLM
  287  VPP(0)  POWER  = PVPP_KLM
  288  VPP(2)  POWER  = PVPP_KLM
